# TIMECARD (Time Appliance Project (Time Card)) — schematic netlist excerpt (pin names and nets, part order shuffled) for the footprints in the layout excerpt that follows; sources: Cadence DE-HDL packaged netlist, KiCad conversion of R4006-B0001-02_R01.brd

U10  CL5003148A  pkg SC70_5V1  page 21
  A  = FPGA_OUT_MACUSBPOWER_EN
  B  = XP5R0V_USB_CONN_DET
  GND  = SG
  Y  = USB_PWR_EN
  VCC  = XP3R3V_FPGA

(kicad_pcb
	(version 20260206)
	(generator "pcbnew")
	(generator_version "10.0")
	(general
		(thickness 1.6)
		(legacy_teardrops no)
	)
	(paper "A4")
	(title_block
		(title "timecard-production-celestica-r4006 — R4006-B0001-02_R01.brd")
		(comment 1 "Time Appliance Project (Time Card) / footprints 760-760 of 1113")
	)
	(layers
		(0 "F.Cu" signal "TOP")
		(4 "In1.Cu" signal "L02_GND1")
		(6 "In2.Cu" signal "L03_SIG1")
		(8 "In3.Cu" signal "L04_GND2")
		(10 "In4.Cu" signal "L05_VCC1")
		(12 "In5.Cu" signal "L06_VCC2")
		(14 "In6.Cu" signal "L07_GND3")
		(16 "In7.Cu" signal "L08_SIG2")
		(18 "In8.Cu" signal "L09_GND4")
		(2 "B.Cu" signal "BOTTOM")
		(9 "F.Adhes" user "F.Adhesive")
		(11 "B.Adhes" user "B.Adhesive")
		(13 "F.Paste" user "Package Geometry/Pastemask Top")
		(15 "B.Paste" user "Package Geometry/Pastemask Bottom")
		(5 "F.SilkS" user "Ref Des/Silkscreen Top")
		(7 "B.SilkS" user "Ref Des/Silkscreen Bottom")
		(1 "F.Mask" user "Board Geometry/Soldermask Top")
		(3 "B.Mask" user "Board Geometry/Soldermask Bottom")
		(17 "Dwgs.User" user "User.Drawings")
		(19 "Cmts.User" user "User.Comments")
		(21 "Eco1.User" user "User.Eco1")
		(23 "Eco2.User" user "User.Eco2")
		(25 "Edge.Cuts" user "Board Geometry/Outline")
		(27 "Margin" user)
		(31 "F.CrtYd" user "Package Geometry/Place Bound Top")
		(29 "B.CrtYd" user "Package Geometry/Place Bound Bottom")
		(35 "F.Fab" user "Ref Des/Assembly Top")
		(33 "B.Fab" user "Ref Des/Assembly Bottom")
	)
	(footprint ""
		(layer "B.Cu")
		(at 61.976 -56.896 -90)
		(property "Reference" "U10"
			(at 0.381 2.19837 270)
			(unlocked yes)
			(layer "B.SilkS")
			(effects
				(font
					(size 0.7874 0.5842)
					(thickness 0.1524)
				)
				(justify mirror)
			)
		)
		(property "Value" ""
			(at 0 0 90)
			(layer "B.Fab")
			(effects
				(font
					(size 1.27 1.27)
				)
				(justify mirror)
			)
		)
		(property "User Part Number" "PARTNUM*"
			(at -0.381 2.97307 270)
			(unlocked yes)
			(layer "Cmts.User")
			(hide yes)
			(effects
				(font
					(size 0.7874 0.5842)
					(thickness 0.1524)
				)
				(justify mirror)
			)
		)
		(property "Device Type" "CL5003148A-G220-10019-01"
			(at -0.4064 2.05867 270)
			(unlocked yes)
			(layer "B.Fab")
			(hide yes)
			(effects
				(font
					(size 0.7874 0.5842)
					(thickness 0.1524)
				)
				(justify mirror)
			)
		)
		(duplicate_pad_numbers_are_jumpers no)
		(fp_line
			(start -0.952754 1.32842)
			(end -0.952754 1.069086)
			(stroke
				(width 0.1)
				(type default)
			)
			(layer "B.SilkS")
		)
		(fp_line
			(start 0.952754 1.32842)
			(end -0.952754 1.32842)
			(stroke
				(width 0.1)
				(type default)
			)
			(layer "B.SilkS")
		)
		(fp_line
			(start -1.9304 1.069086)
			(end -1.9304 -1.069086)
			(stroke
				(width 0.1)
				(type default)
			)
			(layer "B.SilkS")
		)
		(fp_line
			(start -0.952754 1.069086)
			(end -1.9304 1.069086)
			(stroke
				(width 0.1)
				(type default)
			)
			(layer "B.SilkS")
		)
		(fp_line
			(start 0.952754 1.069086)
			(end 0.952754 1.32842)
			(stroke
				(width 0.1)
				(type default)
			)
			(layer "B.SilkS")
		)
		(fp_line
			(start 1.9304 1.069086)
			(end 0.952754 1.069086)
			(stroke
				(width 0.1)
				(type default)
			)
			(layer "B.SilkS")
		)
		(fp_line
			(start -1.9304 -1.069086)
			(end -0.952754 -1.069086)
			(stroke
				(width 0.1)
				(type default)
			)
			(layer "B.SilkS")
		)
		(fp_line
			(start -0.952754 -1.069086)
			(end -0.952754 -1.32842)
			(stroke
				(width 0.1)
				(type default)
			)
			(layer "B.SilkS")
		)
		(fp_line
			(start 0.952754 -1.069086)
			(end 1.9304 -1.069086)
			(stroke
				(width 0.1)
				(type default)
			)
			(layer "B.SilkS")
		)
		(fp_line
			(start 1.9304 -1.069086)
			(end 1.9304 1.069086)
			(stroke
				(width 0.1)
				(type default)
			)
			(layer "B.SilkS")
		)
		(fp_line
			(start -0.952754 -1.32842)
			(end 0.952754 -1.32842)
			(stroke
				(width 0.1)
				(type default)
			)
			(layer "B.SilkS")
		)
		(fp_line
			(start 0.952754 -1.32842)
			(end 0.952754 -1.069086)
			(stroke
				(width 0.1)
				(type default)
			)
			(layer "B.SilkS")
		)
		(fp_poly
			(pts
				(arc
					(start 2.577592 -1.13538)
					(mid 2.577592 -0.37338)
					(end 2.577592 -1.13538)
				)
			)
			(stroke
				(width 0)
				(type default)
			)
			(fill yes)
			(layer "B.SilkS")
		)
		(fp_rect
			(start -2.1844 1.58242)
			(end 2.1844 -1.58242)
			(stroke
				(width 0)
				(type default)
			)
			(fill no)
			(layer "B.CrtYd")
		)
		(fp_line
			(start -0.698754 1.07442)
			(end -0.698754 0.774954)
			(stroke
				(width 0.1)
				(type default)
			)
			(layer "B.Fab")
		)
		(fp_line
			(start 0.450088 1.07442)
			(end 0.450088 -1.07442)
			(stroke
				(width 0.1)
				(type default)
			)
			(layer "B.Fab")
		)
		(fp_line
			(start 0.698754 1.07442)
			(end -0.698754 1.07442)
			(stroke
				(width 0.1)
				(type default)
			)
			(layer "B.Fab")
		)
		(fp_line
			(start 0.698754 0.774954)
			(end 0.698754 1.07442)
			(stroke
				(width 0.1)
				(type default)
			)
			(layer "B.Fab")
		)
		(fp_line
			(start 0.698754 0.124968)
			(end 0.698754 0.525018)
			(stroke
				(width 0.1)
				(type default)
			)
			(layer "B.Fab")
		)
		(fp_line
			(start -0.698754 -0.525018)
			(end -0.698754 0.525018)
			(stroke
				(width 0.1)
				(type default)
			)
			(layer "B.Fab")
		)
		(fp_line
			(start 0.698754 -0.525018)
			(end 0.698754 -0.124968)
			(stroke
				(width 0.1)
				(type default)
			)
			(layer "B.Fab")
		)
		(fp_line
			(start 0.698754 -0.774954)
			(end 0.698754 -1.07442)
			(stroke
				(width 0.1)
				(type default)
			)
			(layer "B.Fab")
		)
		(fp_line
			(start -0.698754 -1.07442)
			(end -0.698754 -0.774954)
			(stroke
				(width 0.1)
				(type default)
			)
			(layer "B.Fab")
		)
		(fp_line
			(start -0.450088 -1.07442)
			(end -0.450088 1.07442)
			(stroke
				(width 0.1)
				(type default)
			)
			(layer "B.Fab")
		)
		(fp_line
			(start 0.698754 -1.07442)
			(end -0.698754 -1.07442)
			(stroke
				(width 0.1)
				(type default)
			)
			(layer "B.Fab")
		)
		(fp_rect
			(start -1.198626 0.774954)
			(end -0.6985 0.525018)
			(stroke
				(width 0)
				(type default)
			)
			(fill no)
			(layer "B.Fab")
		)
		(fp_rect
			(start 0.6985 0.774954)
			(end 1.198626 0.525018)
			(stroke
				(width 0)
				(type default)
			)
			(fill no)
			(layer "B.Fab")
		)
		(fp_rect
			(start 0.6985 0.124968)
			(end 1.198626 -0.124968)
			(stroke
				(width 0)
				(type default)
			)
			(fill no)
			(layer "B.Fab")
		)
		(fp_rect
			(start -1.198626 -0.525018)
			(end -0.6985 -0.774954)
			(stroke
				(width 0)
				(type default)
			)
			(fill no)
			(layer "B.Fab")
		)
		(fp_rect
			(start 0.6985 -0.525018)
			(end 1.198626 -0.774954)
			(stroke
				(width 0)
				(type default)
			)
			(fill no)
			(layer "B.Fab")
		)
		(fp_poly
			(pts
				(arc
					(start 2.577592 -1.13538)
					(mid 2.577592 -0.37338)
					(end 2.577592 -1.13538)
				)
			)
			(stroke
				(width 0)
				(type default)
			)
			(fill yes)
			(layer "B.Fab")
		)
		(fp_text user "4"
			(at -1.41605 1.778 0)
			(unlocked yes)
			(layer "B.SilkS")
			(effects
				(font
					(size 0.635 0.4064)
					(thickness 0.1524)
				)
				(justify mirror)
			)
		)
		(fp_text user "3"
			(at 2.64795 1.524 0)
			(unlocked yes)
			(layer "B.SilkS")
			(effects
				(font
					(size 0.635 0.4064)
					(thickness 0.1524)
				)
				(justify mirror)
			)
		)
		(fp_text user "5"
			(at -1.54305 -1.524 0)
			(unlocked yes)
			(layer "B.SilkS")
			(effects
				(font
					(size 0.635 0.4064)
					(thickness 0.1524)
				)
				(justify mirror)
			)
		)
		(fp_text user "3"
			(at 2.05867 0.889 0)
			(unlocked yes)
			(layer "B.Fab")
			(effects
				(font
					(size 0.7874 0.5842)
					(thickness 0.1524)
				)
				(justify mirror)
			)
		)
		(fp_text user "4"
			(at -1.781302 0.36703 0)
			(unlocked yes)
			(layer "B.Fab")
			(effects
				(font
					(size 0.7874 0.5842)
					(thickness 0.1524)
				)
				(justify mirror)
			)
		)
		(fp_text user "5"
			(at -1.75133 -1.007618 0)
			(unlocked yes)
			(layer "B.Fab")
			(effects
				(font
					(size 0.7874 0.5842)
					(thickness 0.1524)
				)
				(justify mirror)
			)
		)
		(pad "1" smd rect
			(at 1.1938 -0.649986)
			(size 0.3302 0.9652)
			(layers "B.Cu" "B.Mask" "B.Paste")
			(net "FPGA_OUT_MACUSBPOWER_EN")
		)
		(pad "2" smd rect
			(at 1.1938 0)
			(size 0.3302 0.9652)
			(layers "B.Cu" "B.Mask" "B.Paste")
			(net "XP5R0V_USB_CONN_DET")
		)
		(pad "3" smd rect
			(at 1.1938 0.649986)
			(size 0.3302 0.9652)
			(layers "B.Cu" "B.Mask" "B.Paste")
			(net "SG")
		)
		(pad "4" smd rect
			(at -1.1938 0.649986)
			(size 0.3302 0.9652)
			(layers "B.Cu" "B.Mask" "B.Paste")
			(net "USB_PWR_EN")
		)
		(pad "5" smd rect
			(at -1.1938 -0.649986)
			(size 0.3302 0.9652)
			(layers "B.Cu" "B.Mask" "B.Paste")
			(net "XP3R3V_FPGA")
		)
		(zone
			(layer "B.Cu")
			(hatch none 0.5)
			(connect_pads
				(clearance 0)
			)
			(min_thickness 0.25)
			(keepout
				(tracks allowed)
				(vias not_allowed)
				(pads allowed)
				(copperpour not_allowed)
				(footprints allowed)
			)
			(placement
				(enabled no)
				(sheetname "")
			)
			(fill
				(thermal_gap 0.5)
				(thermal_bridge_width 0.5)
				(island_removal_mode 0)
			)
			(polygon
				(pts
					(xy 60.9727 -57.531) (xy 60.9727 -56.261) (xy 62.9793 -56.261) (xy 62.9793 -57.531)
				)
			)
		)
	)
)
